# T6G (Grand Teton) — schematic netlist excerpt (pin names and nets, part order shuffled) for the footprints in the layout excerpt that follows; sources: Cadence DE-HDL packaged netlist, KiCad conversion of 04192023_DAF0TMB3IC0_F0TG_MB_C_brd_V02_OCP.brd

R32  Q_RES  4.7K 1% CHIP  pkg 0402LF  page 131 : A = OCP_SFF_ID0 ; B = GND
C2623  Q_CAP  22UF 4V 20% X6S  pkg C0402  page 70 : A = PVDD11_S3_P0 ; B = GND

(kicad_pcb
	(version 20260206)
	(generator "pcbnew")
	(generator_version "10.0")
	(general
		(thickness 1.6)
		(legacy_teardrops no)
	)
	(paper "A4")
	(title_block
		(title "04192023_DAF0TMB3IC0_F0TG_MB_C_brd_V02_OCP.brd")
		(comment 1 "Grand Teton / footprints 6752-6753 of 8354")
	)
	(layers
		(0 "F.Cu" signal "TOP")
		(4 "In1.Cu" signal "GND")
		(6 "In2.Cu" signal "IN1")
		(8 "In3.Cu" signal "GND1")
		(10 "In4.Cu" signal "IN2")
		(12 "In5.Cu" signal "GND2")
		(14 "In6.Cu" signal "IN3")
		(16 "In7.Cu" signal "GND3")
		(18 "In8.Cu" signal "VCC")
		(20 "In9.Cu" signal "VCC1")
		(22 "In10.Cu" signal "GND4")
		(24 "In11.Cu" signal "IN4")
		(26 "In12.Cu" signal "GND5")
		(28 "In13.Cu" signal "IN5")
		(30 "In14.Cu" signal "GND6")
		(32 "In15.Cu" signal "IN6")
		(34 "In16.Cu" signal "GND7")
		(2 "B.Cu" signal "BOTTOM")
		(9 "F.Adhes" user "F.Adhesive")
		(11 "B.Adhes" user "B.Adhesive")
		(13 "F.Paste" user "Package Geometry/Pastemask Top")
		(15 "B.Paste" user "Package Geometry/Pastemask Bottom")
		(5 "F.SilkS" user "Ref Des/Silkscreen Top")
		(7 "B.SilkS" user "Ref Des/Silkscreen Bottom")
		(1 "F.Mask" user "Board Geometry/Soldermask Top")
		(3 "B.Mask" user "Board Geometry/Soldermask Bottom")
		(17 "Dwgs.User" user "User.Drawings")
		(19 "Cmts.User" user "User.Comments")
		(21 "Eco1.User" user "User.Eco1")
		(23 "Eco2.User" user "User.Eco2")
		(25 "Edge.Cuts" user "Board Geometry/Outline")
		(27 "Margin" user)
		(31 "F.CrtYd" user "Package Geometry/Place Bound Top")
		(29 "B.CrtYd" user "Package Geometry/Place Bound Bottom")
		(35 "F.Fab" user "Ref Des/Assembly Top")
		(33 "B.Fab" user "Ref Des/Assembly Bottom")
	)
	(footprint ""
		(layer "B.Cu")
		(at 447.563748 -10.567162 90)
		(property "Reference" "R32"
			(at 0 0 90)
			(layer "B.SilkS")
			(hide yes)
			(effects
				(font
					(size 1.27 1.27)
				)
				(justify mirror)
			)
		)
		(property "Value" ""
			(at 0 0 90)
			(layer "B.Fab")
			(effects
				(font
					(size 1.27 1.27)
				)
				(justify mirror)
			)
		)
		(duplicate_pad_numbers_are_jumpers no)
		(fp_line
			(start 0.7874 -0.4064)
			(end -0.7874 -0.4064)
			(stroke
				(width 0.1524)
				(type default)
			)
			(layer "B.SilkS")
		)
		(fp_line
			(start -0.7874 -0.4064)
			(end -0.7874 0.4064)
			(stroke
				(width 0.1524)
				(type default)
			)
			(layer "B.SilkS")
		)
		(fp_line
			(start 0.7874 0.4064)
			(end 0.7874 -0.4064)
			(stroke
				(width 0.1524)
				(type default)
			)
			(layer "B.SilkS")
		)
		(fp_line
			(start -0.7874 0.4064)
			(end 0.7874 0.4064)
			(stroke
				(width 0.1524)
				(type default)
			)
			(layer "B.SilkS")
		)
		(fp_line
			(start 0.67945 -0.305054)
			(end 0.12065 -0.305054)
			(stroke
				(width 0.1)
				(type default)
			)
			(layer "B.Fab")
		)
		(fp_line
			(start 0.12065 -0.305054)
			(end 0.12065 -0.2794)
			(stroke
				(width 0.1)
				(type default)
			)
			(layer "B.Fab")
		)
		(fp_line
			(start -0.12065 -0.3048)
			(end -0.67945 -0.3048)
			(stroke
				(width 0.1)
				(type default)
			)
			(layer "B.Fab")
		)
		(fp_line
			(start -0.67945 -0.3048)
			(end -0.67945 0.3048)
			(stroke
				(width 0.1)
				(type default)
			)
			(layer "B.Fab")
		)
		(fp_line
			(start 0.12065 -0.2794)
			(end -0.12065 -0.2794)
			(stroke
				(width 0.1)
				(type default)
			)
			(layer "B.Fab")
		)
		(fp_line
			(start -0.12065 -0.2794)
			(end -0.12065 -0.3048)
			(stroke
				(width 0.1)
				(type default)
			)
			(layer "B.Fab")
		)
		(fp_line
			(start 0.12065 0.2794)
			(end 0.12065 0.3048)
			(stroke
				(width 0.1)
				(type default)
			)
			(layer "B.Fab")
		)
		(fp_line
			(start -0.120396 0.2794)
			(end 0.12065 0.2794)
			(stroke
				(width 0.1)
				(type default)
			)
			(layer "B.Fab")
		)
		(fp_line
			(start 0.67945 0.3048)
			(end 0.67945 -0.305054)
			(stroke
				(width 0.1)
				(type default)
			)
			(layer "B.Fab")
		)
		(fp_line
			(start 0.12065 0.3048)
			(end 0.67945 0.3048)
			(stroke
				(width 0.1)
				(type default)
			)
			(layer "B.Fab")
		)
		(fp_line
			(start -0.120396 0.3048)
			(end -0.120396 0.2794)
			(stroke
				(width 0.1)
				(type default)
			)
			(layer "B.Fab")
		)
		(fp_line
			(start -0.67945 0.3048)
			(end -0.120396 0.3048)
			(stroke
				(width 0.1)
				(type default)
			)
			(layer "B.Fab")
		)
		(pad "1" smd circle
			(at 0.40005 0 270)
			(size 0 0)
			(layers "B.Cu" "B.Mask" "B.Paste")
			(net "OCP_SFF_ID0")
		)
		(pad "2" smd circle
			(at -0.40005 0 270)
			(size 0 0)
			(layers "B.Cu" "B.Mask" "B.Paste")
			(net "GND")
		)
	)
	(footprint ""
		(layer "B.Cu")
		(at 359.994454 -264.86231)
		(property "Reference" "C2623"
			(at 0 0 0)
			(layer "B.SilkS")
			(hide yes)
			(effects
				(font
					(size 1.27 1.27)
				)
				(justify mirror)
			)
		)
		(property "Value" ""
			(at 0 0 0)
			(layer "B.Fab")
			(effects
				(font
					(size 1.27 1.27)
				)
				(justify mirror)
			)
		)
		(duplicate_pad_numbers_are_jumpers no)
		(fp_line
			(start -0.7874 -0.4064)
			(end -0.7874 0.4064)
			(stroke
				(width 0.1524)
				(type default)
			)
			(layer "B.SilkS")
		)
		(fp_line
			(start -0.7874 0.4064)
			(end 0.7874 0.4064)
			(stroke
				(width 0.1524)
				(type default)
			)
			(layer "B.SilkS")
		)
		(fp_line
			(start 0.7874 -0.4064)
			(end -0.7874 -0.4064)
			(stroke
				(width 0.1524)
				(type default)
			)
			(layer "B.SilkS")
		)
		(fp_line
			(start 0.7874 0.4064)
			(end 0.7874 -0.4064)
			(stroke
				(width 0.1524)
				(type default)
			)
			(layer "B.SilkS")
		)
		(fp_line
			(start -0.67945 -0.3048)
			(end -0.67945 0.3048)
			(stroke
				(width 0.1)
				(type default)
			)
			(layer "B.Fab")
		)
		(fp_line
			(start -0.67945 0.3048)
			(end -0.120396 0.3048)
			(stroke
				(width 0.1)
				(type default)
			)
			(layer "B.Fab")
		)
		(fp_line
			(start -0.12065 -0.3048)
			(end -0.67945 -0.3048)
			(stroke
				(width 0.1)
				(type default)
			)
			(layer "B.Fab")
		)
		(fp_line
			(start -0.12065 -0.2794)
			(end -0.12065 -0.3048)
			(stroke
				(width 0.1)
				(type default)
			)
			(layer "B.Fab")
		)
		(fp_line
			(start -0.120396 0.2794)
			(end 0.12065 0.2794)
			(stroke
				(width 0.1)
				(type default)
			)
			(layer "B.Fab")
		)
		(fp_line
			(start -0.120396 0.3048)
			(end -0.120396 0.2794)
			(stroke
				(width 0.1)
				(type default)
			)
			(layer "B.Fab")
		)
		(fp_line
			(start 0.12065 -0.305054)
			(end 0.12065 -0.2794)
			(stroke
				(width 0.1)
				(type default)
			)
			(layer "B.Fab")
		)
		(fp_line
			(start 0.12065 -0.2794)
			(end -0.12065 -0.2794)
			(stroke
				(width 0.1)
				(type default)
			)
			(layer "B.Fab")
		)
		(fp_line
			(start 0.12065 0.2794)
			(end 0.12065 0.3048)
			(stroke
				(width 0.1)
				(type default)
			)
			(layer "B.Fab")
		)
		(fp_line
			(start 0.12065 0.3048)
			(end 0.67945 0.3048)
			(stroke
				(width 0.1)
				(type default)
			)
			(layer "B.Fab")
		)
		(fp_line
			(start 0.67945 -0.305054)
			(end 0.12065 -0.305054)
			(stroke
				(width 0.1)
				(type default)
			)
			(layer "B.Fab")
		)
		(fp_line
			(start 0.67945 0.3048)
			(end 0.67945 -0.305054)
			(stroke
				(width 0.1)
				(type default)
			)
			(layer "B.Fab")
		)
		(pad "1" smd circle
			(at 0.40005 0 180)
			(size 0 0)
			(layers "B.Cu" "B.Mask" "B.Paste")
			(net "PVDD11_S3_P0")
		)
		(pad "2" smd circle
			(at -0.40005 0 180)
			(size 0 0)
			(layers "B.Cu" "B.Mask" "B.Paste")
			(net "GND")
		)
	)
)
